(kicad_pcb
	(version 20260206)
	(generator "pcbnew")
	(generator_version "10.0")
	(general
		(thickness 1.6)
		(legacy_teardrops no)
	)
	(paper "A4")
	(title_block
		(title "01162023_DA0F0TEBIF0_F0T_Expander_BD_F_brd_V02_OCP.brd")
		(comment 1 "Grand Teton / footprints 980-987 of 9728")
	)
	(layers
		(0 "F.Cu" signal "TOP")
		(4 "In1.Cu" signal "GND")
		(6 "In2.Cu" signal "VCC")
		(8 "In3.Cu" signal "VCC1")
		(10 "In4.Cu" signal "GND1")
		(12 "In5.Cu" signal "IN1")
		(14 "In6.Cu" signal "GND2")
		(16 "In7.Cu" signal "IN2")
		(18 "In8.Cu" signal "GND3")
		(20 "In9.Cu" signal "IN3")
		(22 "In10.Cu" signal "GND4")
		(24 "In11.Cu" signal "IN4")
		(26 "In12.Cu" signal "GND5")
		(28 "In13.Cu" signal "IN5")
		(30 "In14.Cu" signal "GND6")
		(32 "In15.Cu" signal "IN6")
		(34 "In16.Cu" signal "GND7")
		(2 "B.Cu" signal "BOTTOM")
		(9 "F.Adhes" user "F.Adhesive")
		(11 "B.Adhes" user "B.Adhesive")
		(13 "F.Paste" user "Package Geometry/Pastemask Top")
		(15 "B.Paste" user "Package Geometry/Pastemask Bottom")
		(5 "F.SilkS" user "Ref Des/Silkscreen Top")
		(7 "B.SilkS" user "Ref Des/Silkscreen Bottom")
		(1 "F.Mask" user "Board Geometry/Soldermask Top")
		(3 "B.Mask" user "Board Geometry/Soldermask Bottom")
		(17 "Dwgs.User" user "User.Drawings")
		(19 "Cmts.User" user "User.Comments")
		(21 "Eco1.User" user "User.Eco1")
		(23 "Eco2.User" user "User.Eco2")
		(25 "Edge.Cuts" user "Board Geometry/Outline")
		(27 "Margin" user)
		(31 "F.CrtYd" user "Package Geometry/Place Bound Top")
		(29 "B.CrtYd" user "Package Geometry/Place Bound Bottom")
		(35 "F.Fab" user "Ref Des/Assembly Top")
		(33 "B.Fab" user "Ref Des/Assembly Bottom")
	)
	(footprint ""
		(layer "F.Cu")
		(at 265.311382 -261.434834)
		(property "Reference" "L123"
			(at 0 0 0)
			(layer "F.SilkS")
			(hide yes)
			(effects
				(font
					(size 1.27 1.27)
				)
			)
		)
		(property "Value" ""
			(at 0 0 0)
			(layer "F.Fab")
			(effects
				(font
					(size 1.27 1.27)
				)
			)
		)
		(duplicate_pad_numbers_are_jumpers no)
		(fp_line
			(start -1.63576 -0.8128)
			(end -1.63576 0.8128)
			(stroke
				(width 0.1524)
				(type default)
			)
			(layer "F.SilkS")
		)
		(fp_line
			(start -1.63576 -0.8128)
			(end 1.63576 -0.8128)
			(stroke
				(width 0.1524)
				(type default)
			)
			(layer "F.SilkS")
		)
		(fp_line
			(start 1.63576 -0.8128)
			(end 1.63576 0.8128)
			(stroke
				(width 0.1524)
				(type default)
			)
			(layer "F.SilkS")
		)
		(fp_line
			(start 1.63576 0.8128)
			(end -1.63576 0.8128)
			(stroke
				(width 0.1524)
				(type default)
			)
			(layer "F.SilkS")
		)
		(fp_line
			(start -1.56083 -0.738632)
			(end -1.56083 0.7366)
			(stroke
				(width 0.1)
				(type default)
			)
			(layer "F.Fab")
		)
		(fp_line
			(start -1.56083 0.7366)
			(end -1.524 0.7366)
			(stroke
				(width 0.1)
				(type default)
			)
			(layer "F.Fab")
		)
		(fp_line
			(start -1.524 0.7366)
			(end 1.524 0.7366)
			(stroke
				(width 0.1)
				(type default)
			)
			(layer "F.Fab")
		)
		(fp_line
			(start 1.524 0.7366)
			(end 1.560576 0.7366)
			(stroke
				(width 0.1)
				(type default)
			)
			(layer "F.Fab")
		)
		(fp_line
			(start 1.560576 -0.738632)
			(end -1.56083 -0.738632)
			(stroke
				(width 0.1)
				(type default)
			)
			(layer "F.Fab")
		)
		(fp_line
			(start 1.560576 0.7366)
			(end 1.560576 -0.738632)
			(stroke
				(width 0.1)
				(type default)
			)
			(layer "F.Fab")
		)
		(pad "1" smd rect
			(at -0.94996 0 180)
			(size 1.1176 1.3716)
			(layers "F.Cu" "F.Mask" "F.Paste")
			(net "P1V8_PLL0_PEX2")
		)
		(pad "2" smd rect
			(at 0.94996 0 180)
			(size 1.1176 1.3716)
			(layers "F.Cu" "F.Mask" "F.Paste")
			(net "PCEPLL3_VDDA18_PEX2")
		)
	)
	(footprint ""
		(layer "F.Cu")
		(at 20.125436 -42.849038 180)
		(property "Reference" "R513"
			(at 0 0 180)
			(layer "F.SilkS")
			(hide yes)
			(effects
				(font
					(size 1.27 1.27)
				)
			)
		)
		(property "Value" ""
			(at 0 0 180)
			(layer "F.Fab")
			(effects
				(font
					(size 1.27 1.27)
				)
			)
		)
		(duplicate_pad_numbers_are_jumpers no)
		(fp_line
			(start 0.7874 0.4064)
			(end -0.7874 0.4064)
			(stroke
				(width 0.1524)
				(type default)
			)
			(layer "F.SilkS")
		)
		(fp_line
			(start 0.7874 -0.4064)
			(end 0.7874 0.4064)
			(stroke
				(width 0.1524)
				(type default)
			)
			(layer "F.SilkS")
		)
		(fp_line
			(start -0.7874 0.4064)
			(end -0.7874 -0.4064)
			(stroke
				(width 0.1524)
				(type default)
			)
			(layer "F.SilkS")
		)
		(fp_line
			(start -0.7874 -0.4064)
			(end 0.7874 -0.4064)
			(stroke
				(width 0.1524)
				(type default)
			)
			(layer "F.SilkS")
		)
		(fp_line
			(start 0.67945 0.3048)
			(end 0.120396 0.3048)
			(stroke
				(width 0.1)
				(type default)
			)
			(layer "F.Fab")
		)
		(fp_line
			(start 0.67945 -0.3048)
			(end 0.67945 0.3048)
			(stroke
				(width 0.1)
				(type default)
			)
			(layer "F.Fab")
		)
		(fp_line
			(start 0.12065 -0.2794)
			(end 0.12065 -0.3048)
			(stroke
				(width 0.1)
				(type default)
			)
			(layer "F.Fab")
		)
		(fp_line
			(start 0.12065 -0.3048)
			(end 0.67945 -0.3048)
			(stroke
				(width 0.1)
				(type default)
			)
			(layer "F.Fab")
		)
		(fp_line
			(start 0.120396 0.3048)
			(end 0.120396 0.2794)
			(stroke
				(width 0.1)
				(type default)
			)
			(layer "F.Fab")
		)
		(fp_line
			(start 0.120396 0.2794)
			(end -0.12065 0.2794)
			(stroke
				(width 0.1)
				(type default)
			)
			(layer "F.Fab")
		)
		(fp_line
			(start -0.12065 0.3048)
			(end -0.67945 0.3048)
			(stroke
				(width 0.1)
				(type default)
			)
			(layer "F.Fab")
		)
		(fp_line
			(start -0.12065 0.2794)
			(end -0.12065 0.3048)
			(stroke
				(width 0.1)
				(type default)
			)
			(layer "F.Fab")
		)
		(fp_line
			(start -0.12065 -0.2794)
			(end 0.12065 -0.2794)
			(stroke
				(width 0.1)
				(type default)
			)
			(layer "F.Fab")
		)
		(fp_line
			(start -0.12065 -0.305054)
			(end -0.12065 -0.2794)
			(stroke
				(width 0.1)
				(type default)
			)
			(layer "F.Fab")
		)
		(fp_line
			(start -0.67945 0.3048)
			(end -0.67945 -0.305054)
			(stroke
				(width 0.1)
				(type default)
			)
			(layer "F.Fab")
		)
		(fp_line
			(start -0.67945 -0.305054)
			(end -0.12065 -0.305054)
			(stroke
				(width 0.1)
				(type default)
			)
			(layer "F.Fab")
		)
		(pad "1" smd circle
			(at -0.40005 0 180)
			(size 0 0)
			(layers "F.Cu" "F.Mask" "F.Paste")
			(net "P12V_SSD0_R")
		)
		(pad "2" smd circle
			(at 0.40005 0 180)
			(size 0 0)
			(layers "F.Cu" "F.Mask" "F.Paste")
			(net "P12V_SSD0_VIN_P")
		)
	)
	(footprint ""
		(layer "F.Cu")
		(at 146.253454 -288.190432)
		(property "Reference" "L110"
			(at 0 0 0)
			(layer "F.SilkS")
			(hide yes)
			(effects
				(font
					(size 1.27 1.27)
				)
			)
		)
		(property "Value" ""
			(at 0 0 0)
			(layer "F.Fab")
			(effects
				(font
					(size 1.27 1.27)
				)
			)
		)
		(duplicate_pad_numbers_are_jumpers no)
		(fp_line
			(start -1.63576 -0.8128)
			(end -1.63576 0.8128)
			(stroke
				(width 0.1524)
				(type default)
			)
			(layer "F.SilkS")
		)
		(fp_line
			(start -1.63576 -0.8128)
			(end 1.63576 -0.8128)
			(stroke
				(width 0.1524)
				(type default)
			)
			(layer "F.SilkS")
		)
		(fp_line
			(start 1.63576 -0.8128)
			(end 1.63576 0.8128)
			(stroke
				(width 0.1524)
				(type default)
			)
			(layer "F.SilkS")
		)
		(fp_line
			(start 1.63576 0.8128)
			(end -1.63576 0.8128)
			(stroke
				(width 0.1524)
				(type default)
			)
			(layer "F.SilkS")
		)
		(fp_line
			(start -1.56083 -0.738632)
			(end -1.56083 0.7366)
			(stroke
				(width 0.1)
				(type default)
			)
			(layer "F.Fab")
		)
		(fp_line
			(start -1.56083 0.7366)
			(end -1.524 0.7366)
			(stroke
				(width 0.1)
				(type default)
			)
			(layer "F.Fab")
		)
		(fp_line
			(start -1.524 0.7366)
			(end 1.524 0.7366)
			(stroke
				(width 0.1)
				(type default)
			)
			(layer "F.Fab")
		)
		(fp_line
			(start 1.524 0.7366)
			(end 1.560576 0.7366)
			(stroke
				(width 0.1)
				(type default)
			)
			(layer "F.Fab")
		)
		(fp_line
			(start 1.560576 -0.738632)
			(end -1.56083 -0.738632)
			(stroke
				(width 0.1)
				(type default)
			)
			(layer "F.Fab")
		)
		(fp_line
			(start 1.560576 0.7366)
			(end 1.560576 -0.738632)
			(stroke
				(width 0.1)
				(type default)
			)
			(layer "F.Fab")
		)
		(pad "1" smd rect
			(at -0.94996 0 180)
			(size 1.1176 1.3716)
			(layers "F.Cu" "F.Mask" "F.Paste")
			(net "P1V8_PLL0_PEX1")
		)
		(pad "2" smd rect
			(at 0.94996 0 180)
			(size 1.1176 1.3716)
			(layers "F.Cu" "F.Mask" "F.Paste")
			(net "PCEPLL6_VDDA18_PEX1")
		)
	)
	(footprint ""
		(layer "F.Cu")
		(at 14.618462 -305.87569 90)
		(property "Reference" "PC222"
			(at 0 0 90)
			(layer "F.SilkS")
			(hide yes)
			(effects
				(font
					(size 1.27 1.27)
				)
			)
		)
		(property "Value" ""
			(at 0 0 90)
			(layer "F.Fab")
			(effects
				(font
					(size 1.27 1.27)
				)
			)
		)
		(duplicate_pad_numbers_are_jumpers no)
		(fp_line
			(start 0.7874 -0.4064)
			(end 0.7874 0.4064)
			(stroke
				(width 0.1524)
				(type default)
			)
			(layer "F.SilkS")
		)
		(fp_line
			(start -0.7874 -0.4064)
			(end 0.7874 -0.4064)
			(stroke
				(width 0.1524)
				(type default)
			)
			(layer "F.SilkS")
		)
		(fp_line
			(start 0.7874 0.4064)
			(end -0.7874 0.4064)
			(stroke
				(width 0.1524)
				(type default)
			)
			(layer "F.SilkS")
		)
		(fp_line
			(start -0.7874 0.4064)
			(end -0.7874 -0.4064)
			(stroke
				(width 0.1524)
				(type default)
			)
			(layer "F.SilkS")
		)
		(fp_line
			(start -0.12065 -0.305054)
			(end -0.12065 -0.2794)
			(stroke
				(width 0.1)
				(type default)
			)
			(layer "F.Fab")
		)
		(fp_line
			(start -0.67945 -0.305054)
			(end -0.12065 -0.305054)
			(stroke
				(width 0.1)
				(type default)
			)
			(layer "F.Fab")
		)
		(fp_line
			(start 0.67945 -0.3048)
			(end 0.67945 0.3048)
			(stroke
				(width 0.1)
				(type default)
			)
			(layer "F.Fab")
		)
		(fp_line
			(start 0.12065 -0.3048)
			(end 0.67945 -0.3048)
			(stroke
				(width 0.1)
				(type default)
			)
			(layer "F.Fab")
		)
		(fp_line
			(start 0.12065 -0.2794)
			(end 0.12065 -0.3048)
			(stroke
				(width 0.1)
				(type default)
			)
			(layer "F.Fab")
		)
		(fp_line
			(start -0.12065 -0.2794)
			(end 0.12065 -0.2794)
			(stroke
				(width 0.1)
				(type default)
			)
			(layer "F.Fab")
		)
		(fp_line
			(start 0.120396 0.2794)
			(end -0.12065 0.2794)
			(stroke
				(width 0.1)
				(type default)
			)
			(layer "F.Fab")
		)
		(fp_line
			(start -0.12065 0.2794)
			(end -0.12065 0.3048)
			(stroke
				(width 0.1)
				(type default)
			)
			(layer "F.Fab")
		)
		(fp_line
			(start 0.67945 0.3048)
			(end 0.120396 0.3048)
			(stroke
				(width 0.1)
				(type default)
			)
			(layer "F.Fab")
		)
		(fp_line
			(start 0.120396 0.3048)
			(end 0.120396 0.2794)
			(stroke
				(width 0.1)
				(type default)
			)
			(layer "F.Fab")
		)
		(fp_line
			(start -0.12065 0.3048)
			(end -0.67945 0.3048)
			(stroke
				(width 0.1)
				(type default)
			)
			(layer "F.Fab")
		)
		(fp_line
			(start -0.67945 0.3048)
			(end -0.67945 -0.305054)
			(stroke
				(width 0.1)
				(type default)
			)
			(layer "F.Fab")
		)
		(pad "1" smd circle
			(at -0.40005 0 90)
			(size 0 0)
			(layers "F.Cu" "F.Mask" "F.Paste")
			(net "P1V25_PEX0_REF")
		)
		(pad "2" smd circle
			(at 0.40005 0 90)
			(size 0 0)
			(layers "F.Cu" "F.Mask" "F.Paste")
			(net "SH_P1V25_PEX0_FB_N")
		)
	)
	(footprint ""
		(layer "F.Cu")
		(at 4.872736 -37.795962 -90)
		(property "Reference" "PR6919"
			(at 0 0 270)
			(layer "F.SilkS")
			(hide yes)
			(effects
				(font
					(size 1.27 1.27)
				)
			)
		)
		(property "Value" ""
			(at 0 0 270)
			(layer "F.Fab")
			(effects
				(font
					(size 1.27 1.27)
				)
			)
		)
		(duplicate_pad_numbers_are_jumpers no)
		(fp_line
			(start -0.7874 0.4064)
			(end -0.7874 -0.4064)
			(stroke
				(width 0.1524)
				(type default)
			)
			(layer "F.SilkS")
		)
		(fp_line
			(start 0.7874 0.4064)
			(end -0.7874 0.4064)
			(stroke
				(width 0.1524)
				(type default)
			)
			(layer "F.SilkS")
		)
		(fp_line
			(start -0.7874 -0.4064)
			(end 0.7874 -0.4064)
			(stroke
				(width 0.1524)
				(type default)
			)
			(layer "F.SilkS")
		)
		(fp_line
			(start 0.7874 -0.4064)
			(end 0.7874 0.4064)
			(stroke
				(width 0.1524)
				(type default)
			)
			(layer "F.SilkS")
		)
		(fp_line
			(start -0.67945 0.3048)
			(end -0.67945 -0.305054)
			(stroke
				(width 0.1)
				(type default)
			)
			(layer "F.Fab")
		)
		(fp_line
			(start -0.12065 0.3048)
			(end -0.67945 0.3048)
			(stroke
				(width 0.1)
				(type default)
			)
			(layer "F.Fab")
		)
		(fp_line
			(start 0.120396 0.3048)
			(end 0.120396 0.2794)
			(stroke
				(width 0.1)
				(type default)
			)
			(layer "F.Fab")
		)
		(fp_line
			(start 0.67945 0.3048)
			(end 0.120396 0.3048)
			(stroke
				(width 0.1)
				(type default)
			)
			(layer "F.Fab")
		)
		(fp_line
			(start -0.12065 0.2794)
			(end -0.12065 0.3048)
			(stroke
				(width 0.1)
				(type default)
			)
			(layer "F.Fab")
		)
		(fp_line
			(start 0.120396 0.2794)
			(end -0.12065 0.2794)
			(stroke
				(width 0.1)
				(type default)
			)
			(layer "F.Fab")
		)
		(fp_line
			(start -0.12065 -0.2794)
			(end 0.12065 -0.2794)
			(stroke
				(width 0.1)
				(type default)
			)
			(layer "F.Fab")
		)
		(fp_line
			(start 0.12065 -0.2794)
			(end 0.12065 -0.3048)
			(stroke
				(width 0.1)
				(type default)
			)
			(layer "F.Fab")
		)
		(fp_line
			(start 0.12065 -0.3048)
			(end 0.67945 -0.3048)
			(stroke
				(width 0.1)
				(type default)
			)
			(layer "F.Fab")
		)
		(fp_line
			(start 0.67945 -0.3048)
			(end 0.67945 0.3048)
			(stroke
				(width 0.1)
				(type default)
			)
			(layer "F.Fab")
		)
		(fp_line
			(start -0.67945 -0.305054)
			(end -0.12065 -0.305054)
			(stroke
				(width 0.1)
				(type default)
			)
			(layer "F.Fab")
		)
		(fp_line
			(start -0.12065 -0.305054)
			(end -0.12065 -0.2794)
			(stroke
				(width 0.1)
				(type default)
			)
			(layer "F.Fab")
		)
		(pad "1" smd circle
			(at -0.40005 0 270)
			(size 0 0)
			(layers "F.Cu" "F.Mask" "F.Paste")
			(net "P3V3_SSD0_CO_MODE")
		)
		(pad "2" smd circle
			(at 0.40005 0 270)
			(size 0 0)
			(layers "F.Cu" "F.Mask" "F.Paste")
			(net "GND")
		)
	)
	(footprint ""
		(layer "F.Cu")
		(at 174.596552 -356.244906 90)
		(property "Reference" "C388"
			(at 0 0 90)
			(layer "F.SilkS")
			(hide yes)
			(effects
				(font
					(size 1.27 1.27)
				)
			)
		)
		(property "Value" ""
			(at 0 0 90)
			(layer "F.Fab")
			(effects
				(font
					(size 1.27 1.27)
				)
			)
		)
		(duplicate_pad_numbers_are_jumpers no)
		(fp_line
			(start 0.299974 -0.150114)
			(end 0.299974 0.150114)
			(stroke
				(width 0.1)
				(type default)
			)
			(layer "F.Fab")
		)
		(fp_line
			(start -0.299974 -0.150114)
			(end 0.299974 -0.150114)
			(stroke
				(width 0.1)
				(type default)
			)
			(layer "F.Fab")
		)
		(fp_line
			(start 0.299974 0.150114)
			(end -0.299974 0.150114)
			(stroke
				(width 0.1)
				(type default)
			)
			(layer "F.Fab")
		)
		(fp_line
			(start -0.299974 0.150114)
			(end -0.299974 -0.150114)
			(stroke
				(width 0.1)
				(type default)
			)
			(layer "F.Fab")
		)
		(pad "1" smd rect
			(at -0.2667 0 90)
			(size 0.3048 0.381)
			(layers "F.Cu" "F.Mask" "F.Paste")
			(net "P5E_PEX1_STN7_TX_DP<119>")
		)
		(pad "2" smd rect
			(at 0.2667 0 90)
			(size 0.3048 0.381)
			(layers "F.Cu" "F.Mask" "F.Paste")
			(net "P5E_PEX1_STN7_TX_C_DP<119>")
		)
	)
	(footprint ""
		(layer "F.Cu")
		(at 233.871008 -82.518758 90)
		(property "Reference" "R6603"
			(at 0 0 90)
			(layer "F.SilkS")
			(hide yes)
			(effects
				(font
					(size 1.27 1.27)
				)
			)
		)
		(property "Value" ""
			(at 0 0 90)
			(layer "F.Fab")
			(effects
				(font
					(size 1.27 1.27)
				)
			)
		)
		(duplicate_pad_numbers_are_jumpers no)
		(fp_line
			(start 0.7874 -0.4064)
			(end 0.7874 0.4064)
			(stroke
				(width 0.1524)
				(type default)
			)
			(layer "F.SilkS")
		)
		(fp_line
			(start -0.7874 -0.4064)
			(end 0.003048 -0.4064)
			(stroke
				(width 0.1524)
				(type default)
			)
			(layer "F.SilkS")
		)
		(fp_line
			(start 0.7874 0.4064)
			(end -0.7874 0.4064)
			(stroke
				(width 0.1524)
				(type default)
			)
			(layer "F.SilkS")
		)
		(fp_line
			(start -0.12065 -0.305054)
			(end -0.12065 -0.2794)
			(stroke
				(width 0.1)
				(type default)
			)
			(layer "F.Fab")
		)
		(fp_line
			(start -0.67945 -0.305054)
			(end -0.12065 -0.305054)
			(stroke
				(width 0.1)
				(type default)
			)
			(layer "F.Fab")
		)
		(fp_line
			(start 0.67945 -0.3048)
			(end 0.67945 0.3048)
			(stroke
				(width 0.1)
				(type default)
			)
			(layer "F.Fab")
		)
		(fp_line
			(start 0.12065 -0.3048)
			(end 0.67945 -0.3048)
			(stroke
				(width 0.1)
				(type default)
			)
			(layer "F.Fab")
		)
		(fp_line
			(start 0.12065 -0.2794)
			(end 0.12065 -0.3048)
			(stroke
				(width 0.1)
				(type default)
			)
			(layer "F.Fab")
		)
		(fp_line
			(start -0.12065 -0.2794)
			(end 0.12065 -0.2794)
			(stroke
				(width 0.1)
				(type default)
			)
			(layer "F.Fab")
		)
		(fp_line
			(start 0.120396 0.2794)
			(end -0.12065 0.2794)
			(stroke
				(width 0.1)
				(type default)
			)
			(layer "F.Fab")
		)
		(fp_line
			(start -0.12065 0.2794)
			(end -0.12065 0.3048)
			(stroke
				(width 0.1)
				(type default)
			)
			(layer "F.Fab")
		)
		(fp_line
			(start 0.67945 0.3048)
			(end 0.120396 0.3048)
			(stroke
				(width 0.1)
				(type default)
			)
			(layer "F.Fab")
		)
		(fp_line
			(start 0.120396 0.3048)
			(end 0.120396 0.2794)
			(stroke
				(width 0.1)
				(type default)
			)
			(layer "F.Fab")
		)
		(fp_line
			(start -0.12065 0.3048)
			(end -0.67945 0.3048)
			(stroke
				(width 0.1)
				(type default)
			)
			(layer "F.Fab")
		)
		(fp_line
			(start -0.67945 0.3048)
			(end -0.67945 -0.305054)
			(stroke
				(width 0.1)
				(type default)
			)
			(layer "F.Fab")
		)
		(pad "1" smd rect
			(at -0.40005 0 270)
			(size 0.4572 0.508)
			(layers "F.Cu" "F.Mask" "F.Paste")
			(net "USB2_CP2108_SDB_DP")
		)
		(pad "2" smd rect
			(at 0.40005 0 270)
			(size 0.4572 0.508)
			(layers "F.Cu" "F.Mask" "F.Paste")
			(net "USB2_FT4232_SDB_R_DP")
		)
	)
	(footprint ""
		(layer "F.Cu")
		(at 16.928846 -208.944972 180)
		(property "Reference" "C4416"
			(at 0 0 180)
			(layer "F.SilkS")
			(hide yes)
			(effects
				(font
					(size 1.27 1.27)
				)
			)
		)
		(property "Value" ""
			(at 0 0 180)
			(layer "F.Fab")
			(effects
				(font
					(size 1.27 1.27)
				)
			)
		)
		(duplicate_pad_numbers_are_jumpers no)
		(fp_line
			(start 1.524 0.762)
			(end -1.524 0.762)
			(stroke
				(width 0.1524)
				(type default)
			)
			(layer "F.SilkS")
		)
		(fp_line
			(start 1.524 -0.762)
			(end 1.524 0.762)
			(stroke
				(width 0.1524)
				(type default)
			)
			(layer "F.SilkS")
		)
		(fp_line
			(start -1.524 0.762)
			(end -1.524 -0.762)
			(stroke
				(width 0.1524)
				(type default)
			)
			(layer "F.SilkS")
		)
		(fp_line
			(start -1.524 -0.762)
			(end 1.524 -0.762)
			(stroke
				(width 0.1524)
				(type default)
			)
			(layer "F.SilkS")
		)
		(fp_line
			(start 1.1049 0.724916)
			(end 1.1049 -0.724916)
			(stroke
				(width 0.1)
				(type default)
			)
			(layer "F.Fab")
		)
		(fp_line
			(start 1.1049 -0.724916)
			(end -1.1049 -0.724916)
			(stroke
				(width 0.1)
				(type default)
			)
			(layer "F.Fab")
		)
		(fp_line
			(start -1.1049 0.724916)
			(end 1.1049 0.724916)
			(stroke
				(width 0.1)
				(type default)
			)
			(layer "F.Fab")
		)
		(fp_line
			(start -1.1049 -0.724916)
			(end -1.1049 0.724916)
			(stroke
				(width 0.1)
				(type default)
			)
			(layer "F.Fab")
		)
		(pad "1" smd rect
			(at -0.889 0)
			(size 1.016 1.27)
			(layers "F.Cu" "F.Mask" "F.Paste")
			(net "P1V8_PLL0_PEX0")
		)
		(pad "2" smd rect
			(at 0.889 0)
			(size 1.016 1.27)
			(layers "F.Cu" "F.Mask" "F.Paste")
			(net "GND")
		)
	)
)
